# S9S_MB_2U (Grand Teton) — schematic netlist excerpt (pin names and nets, part order shuffled) for the footprints in the layout excerpt that follows; sources: Cadence DE-HDL packaged netlist, KiCad conversion of 03242023_DA0F0TMBIJ0_F0T_Motherboard_J_brd_V01_OCP.brd

R34  Q_RES  10K 1% CHIP  pkg 0402LF  page 90 : A = PD_CHE_CPU0_DIMM1_SAA ; B = GND
R279  Q_RES  240 1% EMPTY  pkg 0402LF  page 119 : A = PVNN_TERM_CPU0 ; B = PU_CPU0_SOCKET_ID0

(kicad_pcb
	(version 20260206)
	(generator "pcbnew")
	(generator_version "10.0")
	(general
		(thickness 1.6)
		(legacy_teardrops no)
	)
	(paper "A4")
	(title_block
		(title "03242023_DA0F0TMBIJ0_F0T_Motherboard_J_brd_V01_OCP.brd")
		(comment 1 "Grand Teton / footprints 5495-5496 of 6105")
	)
	(layers
		(0 "F.Cu" signal "TOP")
		(4 "In1.Cu" signal "GND")
		(6 "In2.Cu" signal "IN1")
		(8 "In3.Cu" signal "GND1")
		(10 "In4.Cu" signal "IN2")
		(12 "In5.Cu" signal "GND2")
		(14 "In6.Cu" signal "IN3")
		(16 "In7.Cu" signal "GND3")
		(18 "In8.Cu" signal "VCC")
		(20 "In9.Cu" signal "VCC1")
		(22 "In10.Cu" signal "GND4")
		(24 "In11.Cu" signal "IN4")
		(26 "In12.Cu" signal "GND5")
		(28 "In13.Cu" signal "IN5")
		(30 "In14.Cu" signal "GND6")
		(32 "In15.Cu" signal "IN6")
		(34 "In16.Cu" signal "GND7")
		(2 "B.Cu" signal "BOTTOM")
		(9 "F.Adhes" user "F.Adhesive")
		(11 "B.Adhes" user "B.Adhesive")
		(13 "F.Paste" user "Package Geometry/Pastemask Top")
		(15 "B.Paste" user "Package Geometry/Pastemask Bottom")
		(5 "F.SilkS" user "Ref Des/Silkscreen Top")
		(7 "B.SilkS" user "Ref Des/Silkscreen Bottom")
		(1 "F.Mask" user "Board Geometry/Soldermask Top")
		(3 "B.Mask" user "Board Geometry/Soldermask Bottom")
		(17 "Dwgs.User" user "User.Drawings")
		(19 "Cmts.User" user "User.Comments")
		(21 "Eco1.User" user "User.Eco1")
		(23 "Eco2.User" user "User.Eco2")
		(25 "Edge.Cuts" user "Board Geometry/Outline")
		(27 "Margin" user)
		(31 "F.CrtYd" user "Package Geometry/Place Bound Top")
		(29 "B.CrtYd" user "Package Geometry/Place Bound Bottom")
		(35 "F.Fab" user "Ref Des/Assembly Top")
		(33 "B.Fab" user "Ref Des/Assembly Bottom")
	)
	(footprint ""
		(layer "B.Cu")
		(at 408.124152 -193.08953 -90)
		(property "Reference" "R279"
			(at 0 0 90)
			(layer "B.SilkS")
			(hide yes)
			(effects
				(font
					(size 1.27 1.27)
				)
				(justify mirror)
			)
		)
		(property "Value" ""
			(at 0 0 90)
			(layer "B.Fab")
			(effects
				(font
					(size 1.27 1.27)
				)
				(justify mirror)
			)
		)
		(duplicate_pad_numbers_are_jumpers no)
		(fp_line
			(start -0.7874 0.4064)
			(end 0.7874 0.4064)
			(stroke
				(width 0.1524)
				(type default)
			)
			(layer "B.SilkS")
		)
		(fp_line
			(start 0.7874 0.4064)
			(end 0.7874 -0.4064)
			(stroke
				(width 0.1524)
				(type default)
			)
			(layer "B.SilkS")
		)
		(fp_line
			(start -0.7874 -0.4064)
			(end -0.7874 0.4064)
			(stroke
				(width 0.1524)
				(type default)
			)
			(layer "B.SilkS")
		)
		(fp_line
			(start 0.7874 -0.4064)
			(end -0.7874 -0.4064)
			(stroke
				(width 0.1524)
				(type default)
			)
			(layer "B.SilkS")
		)
		(fp_line
			(start -0.67945 0.3048)
			(end -0.120396 0.3048)
			(stroke
				(width 0.1)
				(type default)
			)
			(layer "B.Fab")
		)
		(fp_line
			(start -0.120396 0.3048)
			(end -0.120396 0.2794)
			(stroke
				(width 0.1)
				(type default)
			)
			(layer "B.Fab")
		)
		(fp_line
			(start 0.12065 0.3048)
			(end 0.67945 0.3048)
			(stroke
				(width 0.1)
				(type default)
			)
			(layer "B.Fab")
		)
		(fp_line
			(start 0.67945 0.3048)
			(end 0.67945 -0.305054)
			(stroke
				(width 0.1)
				(type default)
			)
			(layer "B.Fab")
		)
		(fp_line
			(start -0.120396 0.2794)
			(end 0.12065 0.2794)
			(stroke
				(width 0.1)
				(type default)
			)
			(layer "B.Fab")
		)
		(fp_line
			(start 0.12065 0.2794)
			(end 0.12065 0.3048)
			(stroke
				(width 0.1)
				(type default)
			)
			(layer "B.Fab")
		)
		(fp_line
			(start -0.12065 -0.2794)
			(end -0.12065 -0.3048)
			(stroke
				(width 0.1)
				(type default)
			)
			(layer "B.Fab")
		)
		(fp_line
			(start 0.12065 -0.2794)
			(end -0.12065 -0.2794)
			(stroke
				(width 0.1)
				(type default)
			)
			(layer "B.Fab")
		)
		(fp_line
			(start -0.67945 -0.3048)
			(end -0.67945 0.3048)
			(stroke
				(width 0.1)
				(type default)
			)
			(layer "B.Fab")
		)
		(fp_line
			(start -0.12065 -0.3048)
			(end -0.67945 -0.3048)
			(stroke
				(width 0.1)
				(type default)
			)
			(layer "B.Fab")
		)
		(fp_line
			(start 0.12065 -0.305054)
			(end 0.12065 -0.2794)
			(stroke
				(width 0.1)
				(type default)
			)
			(layer "B.Fab")
		)
		(fp_line
			(start 0.67945 -0.305054)
			(end 0.12065 -0.305054)
			(stroke
				(width 0.1)
				(type default)
			)
			(layer "B.Fab")
		)
		(pad "1" smd circle
			(at 0.40005 0 90)
			(size 0 0)
			(layers "B.Cu" "B.Mask" "B.Paste")
			(net "PVNN_TERM_CPU0")
		)
		(pad "2" smd circle
			(at -0.40005 0 90)
			(size 0 0)
			(layers "B.Cu" "B.Mask" "B.Paste")
			(net "PU_CPU0_SOCKET_ID0")
		)
	)
	(footprint ""
		(layer "B.Cu")
		(at 416.080956 -318.730376)
		(property "Reference" "R34"
			(at 0 0 0)
			(layer "B.SilkS")
			(hide yes)
			(effects
				(font
					(size 1.27 1.27)
				)
				(justify mirror)
			)
		)
		(property "Value" ""
			(at 0 0 0)
			(layer "B.Fab")
			(effects
				(font
					(size 1.27 1.27)
				)
				(justify mirror)
			)
		)
		(duplicate_pad_numbers_are_jumpers no)
		(fp_line
			(start -0.7874 -0.4064)
			(end -0.7874 0.4064)
			(stroke
				(width 0.1524)
				(type default)
			)
			(layer "B.SilkS")
		)
		(fp_line
			(start -0.7874 0.4064)
			(end 0.7874 0.4064)
			(stroke
				(width 0.1524)
				(type default)
			)
			(layer "B.SilkS")
		)
		(fp_line
			(start 0.7874 -0.4064)
			(end -0.7874 -0.4064)
			(stroke
				(width 0.1524)
				(type default)
			)
			(layer "B.SilkS")
		)
		(fp_line
			(start 0.7874 0.4064)
			(end 0.7874 -0.4064)
			(stroke
				(width 0.1524)
				(type default)
			)
			(layer "B.SilkS")
		)
		(fp_line
			(start -0.67945 -0.3048)
			(end -0.67945 0.3048)
			(stroke
				(width 0.1)
				(type default)
			)
			(layer "B.Fab")
		)
		(fp_line
			(start -0.67945 0.3048)
			(end -0.120396 0.3048)
			(stroke
				(width 0.1)
				(type default)
			)
			(layer "B.Fab")
		)
		(fp_line
			(start -0.12065 -0.3048)
			(end -0.67945 -0.3048)
			(stroke
				(width 0.1)
				(type default)
			)
			(layer "B.Fab")
		)
		(fp_line
			(start -0.12065 -0.2794)
			(end -0.12065 -0.3048)
			(stroke
				(width 0.1)
				(type default)
			)
			(layer "B.Fab")
		)
		(fp_line
			(start -0.120396 0.2794)
			(end 0.12065 0.2794)
			(stroke
				(width 0.1)
				(type default)
			)
			(layer "B.Fab")
		)
		(fp_line
			(start -0.120396 0.3048)
			(end -0.120396 0.2794)
			(stroke
				(width 0.1)
				(type default)
			)
			(layer "B.Fab")
		)
		(fp_line
			(start 0.12065 -0.305054)
			(end 0.12065 -0.2794)
			(stroke
				(width 0.1)
				(type default)
			)
			(layer "B.Fab")
		)
		(fp_line
			(start 0.12065 -0.2794)
			(end -0.12065 -0.2794)
			(stroke
				(width 0.1)
				(type default)
			)
			(layer "B.Fab")
		)
		(fp_line
			(start 0.12065 0.2794)
			(end 0.12065 0.3048)
			(stroke
				(width 0.1)
				(type default)
			)
			(layer "B.Fab")
		)
		(fp_line
			(start 0.12065 0.3048)
			(end 0.67945 0.3048)
			(stroke
				(width 0.1)
				(type default)
			)
			(layer "B.Fab")
		)
		(fp_line
			(start 0.67945 -0.305054)
			(end 0.12065 -0.305054)
			(stroke
				(width 0.1)
				(type default)
			)
			(layer "B.Fab")
		)
		(fp_line
			(start 0.67945 0.3048)
			(end 0.67945 -0.305054)
			(stroke
				(width 0.1)
				(type default)
			)
			(layer "B.Fab")
		)
		(pad "1" smd circle
			(at 0.40005 0 180)
			(size 0 0)
			(layers "B.Cu" "B.Mask" "B.Paste")
			(net "PD_CHE_CPU0_DIMM1_SAA")
		)
		(pad "2" smd circle
			(at -0.40005 0 180)
			(size 0 0)
			(layers "B.Cu" "B.Mask" "B.Paste")
			(net "GND")
		)
	)
)
